# T6G (Grand Teton) — schematic netlist excerpt (pin names and nets, part order shuffled) for the footprints in the layout excerpt that follows; sources: Cadence DE-HDL packaged netlist, KiCad conversion of 04192023_DAF0TMB3IC0_F0TG_MB_C_brd_V02_OCP.brd

R862  Q_RES  0 5% CHIP  pkg 0402LF  page 54 : A = CPU1_XTRIG_R2_L6 ; B = CPU1_XTRIG_L6
PR257  Q_RES  2.2 1% CHIP  pkg 0402LF  page 218 : A = PVDDCR_CPU1_P1_PVCC ; B = PVDDCR_CPU1_P1_VCC2

(kicad_pcb
	(version 20260206)
	(generator "pcbnew")
	(generator_version "10.0")
	(general
		(thickness 1.6)
		(legacy_teardrops no)
	)
	(paper "A4")
	(title_block
		(title "04192023_DAF0TMB3IC0_F0TG_MB_C_brd_V02_OCP.brd")
		(comment 1 "Grand Teton / footprints 7449-7450 of 8354")
	)
	(layers
		(0 "F.Cu" signal "TOP")
		(4 "In1.Cu" signal "GND")
		(6 "In2.Cu" signal "IN1")
		(8 "In3.Cu" signal "GND1")
		(10 "In4.Cu" signal "IN2")
		(12 "In5.Cu" signal "GND2")
		(14 "In6.Cu" signal "IN3")
		(16 "In7.Cu" signal "GND3")
		(18 "In8.Cu" signal "VCC")
		(20 "In9.Cu" signal "VCC1")
		(22 "In10.Cu" signal "GND4")
		(24 "In11.Cu" signal "IN4")
		(26 "In12.Cu" signal "GND5")
		(28 "In13.Cu" signal "IN5")
		(30 "In14.Cu" signal "GND6")
		(32 "In15.Cu" signal "IN6")
		(34 "In16.Cu" signal "GND7")
		(2 "B.Cu" signal "BOTTOM")
		(9 "F.Adhes" user "F.Adhesive")
		(11 "B.Adhes" user "B.Adhesive")
		(13 "F.Paste" user "Package Geometry/Pastemask Top")
		(15 "B.Paste" user "Package Geometry/Pastemask Bottom")
		(5 "F.SilkS" user "Ref Des/Silkscreen Top")
		(7 "B.SilkS" user "Ref Des/Silkscreen Bottom")
		(1 "F.Mask" user "Board Geometry/Soldermask Top")
		(3 "B.Mask" user "Board Geometry/Soldermask Bottom")
		(17 "Dwgs.User" user "User.Drawings")
		(19 "Cmts.User" user "User.Comments")
		(21 "Eco1.User" user "User.Eco1")
		(23 "Eco2.User" user "User.Eco2")
		(25 "Edge.Cuts" user "Board Geometry/Outline")
		(27 "Margin" user)
		(31 "F.CrtYd" user "Package Geometry/Place Bound Top")
		(29 "B.CrtYd" user "Package Geometry/Place Bound Bottom")
		(35 "F.Fab" user "Ref Des/Assembly Top")
		(33 "B.Fab" user "Ref Des/Assembly Bottom")
	)
	(footprint ""
		(layer "B.Cu")
		(at 76.453746 -336.05216 -90)
		(property "Reference" "PR257"
			(at 0 0 90)
			(layer "B.SilkS")
			(hide yes)
			(effects
				(font
					(size 1.27 1.27)
				)
				(justify mirror)
			)
		)
		(property "Value" ""
			(at 0 0 90)
			(layer "B.Fab")
			(effects
				(font
					(size 1.27 1.27)
				)
				(justify mirror)
			)
		)
		(duplicate_pad_numbers_are_jumpers no)
		(fp_line
			(start -0.7874 0.4064)
			(end 0.7874 0.4064)
			(stroke
				(width 0.1524)
				(type default)
			)
			(layer "B.SilkS")
		)
		(fp_line
			(start 0.7874 0.4064)
			(end 0.7874 -0.4064)
			(stroke
				(width 0.1524)
				(type default)
			)
			(layer "B.SilkS")
		)
		(fp_line
			(start -0.7874 -0.4064)
			(end -0.7874 0.4064)
			(stroke
				(width 0.1524)
				(type default)
			)
			(layer "B.SilkS")
		)
		(fp_line
			(start 0.7874 -0.4064)
			(end -0.7874 -0.4064)
			(stroke
				(width 0.1524)
				(type default)
			)
			(layer "B.SilkS")
		)
		(fp_line
			(start -0.67945 0.3048)
			(end -0.120396 0.3048)
			(stroke
				(width 0.1)
				(type default)
			)
			(layer "B.Fab")
		)
		(fp_line
			(start -0.120396 0.3048)
			(end -0.120396 0.2794)
			(stroke
				(width 0.1)
				(type default)
			)
			(layer "B.Fab")
		)
		(fp_line
			(start 0.12065 0.3048)
			(end 0.67945 0.3048)
			(stroke
				(width 0.1)
				(type default)
			)
			(layer "B.Fab")
		)
		(fp_line
			(start 0.67945 0.3048)
			(end 0.67945 -0.305054)
			(stroke
				(width 0.1)
				(type default)
			)
			(layer "B.Fab")
		)
		(fp_line
			(start -0.120396 0.2794)
			(end 0.12065 0.2794)
			(stroke
				(width 0.1)
				(type default)
			)
			(layer "B.Fab")
		)
		(fp_line
			(start 0.12065 0.2794)
			(end 0.12065 0.3048)
			(stroke
				(width 0.1)
				(type default)
			)
			(layer "B.Fab")
		)
		(fp_line
			(start -0.12065 -0.2794)
			(end -0.12065 -0.3048)
			(stroke
				(width 0.1)
				(type default)
			)
			(layer "B.Fab")
		)
		(fp_line
			(start 0.12065 -0.2794)
			(end -0.12065 -0.2794)
			(stroke
				(width 0.1)
				(type default)
			)
			(layer "B.Fab")
		)
		(fp_line
			(start -0.67945 -0.3048)
			(end -0.67945 0.3048)
			(stroke
				(width 0.1)
				(type default)
			)
			(layer "B.Fab")
		)
		(fp_line
			(start -0.12065 -0.3048)
			(end -0.67945 -0.3048)
			(stroke
				(width 0.1)
				(type default)
			)
			(layer "B.Fab")
		)
		(fp_line
			(start 0.12065 -0.305054)
			(end 0.12065 -0.2794)
			(stroke
				(width 0.1)
				(type default)
			)
			(layer "B.Fab")
		)
		(fp_line
			(start 0.67945 -0.305054)
			(end 0.12065 -0.305054)
			(stroke
				(width 0.1)
				(type default)
			)
			(layer "B.Fab")
		)
		(pad "1" smd circle
			(at 0.40005 0 90)
			(size 0 0)
			(layers "B.Cu" "B.Mask" "B.Paste")
			(net "PVDDCR_CPU1_P1_PVCC")
		)
		(pad "2" smd circle
			(at -0.40005 0 90)
			(size 0 0)
			(layers "B.Cu" "B.Mask" "B.Paste")
			(net "PVDDCR_CPU1_P1_VCC2")
		)
	)
	(footprint ""
		(layer "B.Cu")
		(at 90.503502 -207.41005 90)
		(property "Reference" "R862"
			(at 0 0 90)
			(layer "B.SilkS")
			(hide yes)
			(effects
				(font
					(size 1.27 1.27)
				)
				(justify mirror)
			)
		)
		(property "Value" ""
			(at 0 0 90)
			(layer "B.Fab")
			(effects
				(font
					(size 1.27 1.27)
				)
				(justify mirror)
			)
		)
		(duplicate_pad_numbers_are_jumpers no)
		(fp_line
			(start 0.7874 -0.4064)
			(end -0.7874 -0.4064)
			(stroke
				(width 0.1524)
				(type default)
			)
			(layer "B.SilkS")
		)
		(fp_line
			(start -0.7874 -0.4064)
			(end -0.7874 0.4064)
			(stroke
				(width 0.1524)
				(type default)
			)
			(layer "B.SilkS")
		)
		(fp_line
			(start 0.7874 0.4064)
			(end 0.7874 -0.4064)
			(stroke
				(width 0.1524)
				(type default)
			)
			(layer "B.SilkS")
		)
		(fp_line
			(start -0.7874 0.4064)
			(end 0.7874 0.4064)
			(stroke
				(width 0.1524)
				(type default)
			)
			(layer "B.SilkS")
		)
		(fp_line
			(start 0.67945 -0.305054)
			(end 0.12065 -0.305054)
			(stroke
				(width 0.1)
				(type default)
			)
			(layer "B.Fab")
		)
		(fp_line
			(start 0.12065 -0.305054)
			(end 0.12065 -0.2794)
			(stroke
				(width 0.1)
				(type default)
			)
			(layer "B.Fab")
		)
		(fp_line
			(start -0.12065 -0.3048)
			(end -0.67945 -0.3048)
			(stroke
				(width 0.1)
				(type default)
			)
			(layer "B.Fab")
		)
		(fp_line
			(start -0.67945 -0.3048)
			(end -0.67945 0.3048)
			(stroke
				(width 0.1)
				(type default)
			)
			(layer "B.Fab")
		)
		(fp_line
			(start 0.12065 -0.2794)
			(end -0.12065 -0.2794)
			(stroke
				(width 0.1)
				(type default)
			)
			(layer "B.Fab")
		)
		(fp_line
			(start -0.12065 -0.2794)
			(end -0.12065 -0.3048)
			(stroke
				(width 0.1)
				(type default)
			)
			(layer "B.Fab")
		)
		(fp_line
			(start 0.12065 0.2794)
			(end 0.12065 0.3048)
			(stroke
				(width 0.1)
				(type default)
			)
			(layer "B.Fab")
		)
		(fp_line
			(start -0.120396 0.2794)
			(end 0.12065 0.2794)
			(stroke
				(width 0.1)
				(type default)
			)
			(layer "B.Fab")
		)
		(fp_line
			(start 0.67945 0.3048)
			(end 0.67945 -0.305054)
			(stroke
				(width 0.1)
				(type default)
			)
			(layer "B.Fab")
		)
		(fp_line
			(start 0.12065 0.3048)
			(end 0.67945 0.3048)
			(stroke
				(width 0.1)
				(type default)
			)
			(layer "B.Fab")
		)
		(fp_line
			(start -0.120396 0.3048)
			(end -0.120396 0.2794)
			(stroke
				(width 0.1)
				(type default)
			)
			(layer "B.Fab")
		)
		(fp_line
			(start -0.67945 0.3048)
			(end -0.120396 0.3048)
			(stroke
				(width 0.1)
				(type default)
			)
			(layer "B.Fab")
		)
		(pad "1" smd circle
			(at 0.40005 0 270)
			(size 0 0)
			(layers "B.Cu" "B.Mask" "B.Paste")
			(net "CPU1_XTRIG_R2_L6")
		)
		(pad "2" smd circle
			(at -0.40005 0 270)
			(size 0 0)
			(layers "B.Cu" "B.Mask" "B.Paste")
			(net "CPU1_XTRIG_L6")
		)
	)
)
